# SCM (Grand Teton) — schematic netlist excerpt (pin names and nets, part order shuffled) for the footprints in the layout excerpt that follows; sources: Cadence DE-HDL packaged netlist, KiCad conversion of 12092022_DA0F0TMDCD0_F0T_Management_Board_D_brd_V3_OCP.brd

R634  Q_RES  0 5% CHIP  pkg 0402LF  page 34 : A = FM_JTAG_BMC_MUX_SEL ; B = FM_JTAG_BMC_MUX_SEL_R2
R557  Q_RES  4.7K 1% CHIP  pkg 0402LF  page 21 : A = P3V3_AUX ; B = SPI_BMC_CS0_FLASH_R_N

(kicad_pcb
	(version 20260206)
	(generator "pcbnew")
	(generator_version "10.0")
	(general
		(thickness 1.6)
		(legacy_teardrops no)
	)
	(paper "A4")
	(title_block
		(title "12092022_DA0F0TMDCD0_F0T_Management_Board_D_brd_V3_OCP.brd")
		(comment 1 "Grand Teton / footprints 547-548 of 1440")
	)
	(layers
		(0 "F.Cu" signal "TOP")
		(4 "In1.Cu" signal "GND")
		(6 "In2.Cu" signal "IN1")
		(8 "In3.Cu" signal "GND1")
		(10 "In4.Cu" signal "IN2")
		(12 "In5.Cu" signal "VCC")
		(14 "In6.Cu" signal "VCC1")
		(16 "In7.Cu" signal "IN3")
		(18 "In8.Cu" signal "GND2")
		(20 "In9.Cu" signal "IN4")
		(22 "In10.Cu" signal "GND3")
		(2 "B.Cu" signal "BOTTOM")
		(9 "F.Adhes" user "F.Adhesive")
		(11 "B.Adhes" user "B.Adhesive")
		(13 "F.Paste" user "Package Geometry/Pastemask Top")
		(15 "B.Paste" user "Package Geometry/Pastemask Bottom")
		(5 "F.SilkS" user "Ref Des/Silkscreen Top")
		(7 "B.SilkS" user "Ref Des/Silkscreen Bottom")
		(1 "F.Mask" user "Board Geometry/Soldermask Top")
		(3 "B.Mask" user "Board Geometry/Soldermask Bottom")
		(17 "Dwgs.User" user "User.Drawings")
		(19 "Cmts.User" user "User.Comments")
		(21 "Eco1.User" user "User.Eco1")
		(23 "Eco2.User" user "User.Eco2")
		(25 "Edge.Cuts" user "Board Geometry/Outline")
		(27 "Margin" user)
		(31 "F.CrtYd" user "Package Geometry/Place Bound Top")
		(29 "B.CrtYd" user "Package Geometry/Place Bound Bottom")
		(35 "F.Fab" user "Ref Des/Assembly Top")
		(33 "B.Fab" user "Ref Des/Assembly Bottom")
	)
	(footprint ""
		(layer "F.Cu")
		(at 23.064216 -84.28228 90)
		(property "Reference" "R634"
			(at 0 0 90)
			(layer "F.SilkS")
			(hide yes)
			(effects
				(font
					(size 1.27 1.27)
				)
			)
		)
		(property "Value" ""
			(at 0 0 90)
			(layer "F.Fab")
			(effects
				(font
					(size 1.27 1.27)
				)
			)
		)
		(duplicate_pad_numbers_are_jumpers no)
		(fp_line
			(start 0.7874 -0.4064)
			(end 0.7874 0.4064)
			(stroke
				(width 0.1524)
				(type default)
			)
			(layer "F.SilkS")
		)
		(fp_line
			(start -0.7874 -0.4064)
			(end 0.7874 -0.4064)
			(stroke
				(width 0.1524)
				(type default)
			)
			(layer "F.SilkS")
		)
		(fp_line
			(start 0.7874 0.4064)
			(end -0.7874 0.4064)
			(stroke
				(width 0.1524)
				(type default)
			)
			(layer "F.SilkS")
		)
		(fp_line
			(start -0.7874 0.4064)
			(end -0.7874 -0.4064)
			(stroke
				(width 0.1524)
				(type default)
			)
			(layer "F.SilkS")
		)
		(fp_line
			(start -0.12065 -0.305054)
			(end -0.12065 -0.2794)
			(stroke
				(width 0.1)
				(type default)
			)
			(layer "F.Fab")
		)
		(fp_line
			(start -0.67945 -0.305054)
			(end -0.12065 -0.305054)
			(stroke
				(width 0.1)
				(type default)
			)
			(layer "F.Fab")
		)
		(fp_line
			(start 0.67945 -0.3048)
			(end 0.67945 0.3048)
			(stroke
				(width 0.1)
				(type default)
			)
			(layer "F.Fab")
		)
		(fp_line
			(start 0.12065 -0.3048)
			(end 0.67945 -0.3048)
			(stroke
				(width 0.1)
				(type default)
			)
			(layer "F.Fab")
		)
		(fp_line
			(start 0.12065 -0.2794)
			(end 0.12065 -0.3048)
			(stroke
				(width 0.1)
				(type default)
			)
			(layer "F.Fab")
		)
		(fp_line
			(start -0.12065 -0.2794)
			(end 0.12065 -0.2794)
			(stroke
				(width 0.1)
				(type default)
			)
			(layer "F.Fab")
		)
		(fp_line
			(start 0.120396 0.2794)
			(end -0.12065 0.2794)
			(stroke
				(width 0.1)
				(type default)
			)
			(layer "F.Fab")
		)
		(fp_line
			(start -0.12065 0.2794)
			(end -0.12065 0.3048)
			(stroke
				(width 0.1)
				(type default)
			)
			(layer "F.Fab")
		)
		(fp_line
			(start 0.67945 0.3048)
			(end 0.120396 0.3048)
			(stroke
				(width 0.1)
				(type default)
			)
			(layer "F.Fab")
		)
		(fp_line
			(start 0.120396 0.3048)
			(end 0.120396 0.2794)
			(stroke
				(width 0.1)
				(type default)
			)
			(layer "F.Fab")
		)
		(fp_line
			(start -0.12065 0.3048)
			(end -0.67945 0.3048)
			(stroke
				(width 0.1)
				(type default)
			)
			(layer "F.Fab")
		)
		(fp_line
			(start -0.67945 0.3048)
			(end -0.67945 -0.305054)
			(stroke
				(width 0.1)
				(type default)
			)
			(layer "F.Fab")
		)
		(pad "1" smd circle
			(at -0.40005 0 90)
			(size 0 0)
			(layers "F.Cu" "F.Mask" "F.Paste")
			(net "FM_JTAG_BMC_MUX_SEL")
		)
		(pad "2" smd circle
			(at 0.40005 0 90)
			(size 0 0)
			(layers "F.Cu" "F.Mask" "F.Paste")
			(net "FM_JTAG_BMC_MUX_SEL_R2")
		)
	)
	(footprint ""
		(layer "F.Cu")
		(at 39.826946 -79.64424 180)
		(property "Reference" "R557"
			(at 0 0 180)
			(layer "F.SilkS")
			(hide yes)
			(effects
				(font
					(size 1.27 1.27)
				)
			)
		)
		(property "Value" ""
			(at 0 0 180)
			(layer "F.Fab")
			(effects
				(font
					(size 1.27 1.27)
				)
			)
		)
		(duplicate_pad_numbers_are_jumpers no)
		(fp_line
			(start 0.7874 0.4064)
			(end -0.7874 0.4064)
			(stroke
				(width 0.1524)
				(type default)
			)
			(layer "F.SilkS")
		)
		(fp_line
			(start 0.7874 -0.4064)
			(end 0.7874 0.4064)
			(stroke
				(width 0.1524)
				(type default)
			)
			(layer "F.SilkS")
		)
		(fp_line
			(start -0.7874 0.4064)
			(end -0.7874 -0.4064)
			(stroke
				(width 0.1524)
				(type default)
			)
			(layer "F.SilkS")
		)
		(fp_line
			(start -0.7874 -0.4064)
			(end 0.7874 -0.4064)
			(stroke
				(width 0.1524)
				(type default)
			)
			(layer "F.SilkS")
		)
		(fp_line
			(start 0.67945 0.3048)
			(end 0.120396 0.3048)
			(stroke
				(width 0.1)
				(type default)
			)
			(layer "F.Fab")
		)
		(fp_line
			(start 0.67945 -0.3048)
			(end 0.67945 0.3048)
			(stroke
				(width 0.1)
				(type default)
			)
			(layer "F.Fab")
		)
		(fp_line
			(start 0.12065 -0.2794)
			(end 0.12065 -0.3048)
			(stroke
				(width 0.1)
				(type default)
			)
			(layer "F.Fab")
		)
		(fp_line
			(start 0.12065 -0.3048)
			(end 0.67945 -0.3048)
			(stroke
				(width 0.1)
				(type default)
			)
			(layer "F.Fab")
		)
		(fp_line
			(start 0.120396 0.3048)
			(end 0.120396 0.2794)
			(stroke
				(width 0.1)
				(type default)
			)
			(layer "F.Fab")
		)
		(fp_line
			(start 0.120396 0.2794)
			(end -0.12065 0.2794)
			(stroke
				(width 0.1)
				(type default)
			)
			(layer "F.Fab")
		)
		(fp_line
			(start -0.12065 0.3048)
			(end -0.67945 0.3048)
			(stroke
				(width 0.1)
				(type default)
			)
			(layer "F.Fab")
		)
		(fp_line
			(start -0.12065 0.2794)
			(end -0.12065 0.3048)
			(stroke
				(width 0.1)
				(type default)
			)
			(layer "F.Fab")
		)
		(fp_line
			(start -0.12065 -0.2794)
			(end 0.12065 -0.2794)
			(stroke
				(width 0.1)
				(type default)
			)
			(layer "F.Fab")
		)
		(fp_line
			(start -0.12065 -0.305054)
			(end -0.12065 -0.2794)
			(stroke
				(width 0.1)
				(type default)
			)
			(layer "F.Fab")
		)
		(fp_line
			(start -0.67945 0.3048)
			(end -0.67945 -0.305054)
			(stroke
				(width 0.1)
				(type default)
			)
			(layer "F.Fab")
		)
		(fp_line
			(start -0.67945 -0.305054)
			(end -0.12065 -0.305054)
			(stroke
				(width 0.1)
				(type default)
			)
			(layer "F.Fab")
		)
		(pad "1" smd circle
			(at -0.40005 0 180)
			(size 0 0)
			(layers "F.Cu" "F.Mask" "F.Paste")
			(net "P3V3_AUX")
		)
		(pad "2" smd circle
			(at 0.40005 0 180)
			(size 0 0)
			(layers "F.Cu" "F.Mask" "F.Paste")
			(net "SPI_BMC_CS0_FLASH_R_N")
		)
	)
)
